FILE_TYPE = CONNECTIVITY;
{Allegro Design Entry HDL 16.6-p007 (v16-6-112F) 10/10/2012}
"PAGE_NUMBER" = 61;
0"NC";
1"M_L_DQS_DP<17:0>";
2"M_L_DQS_DN<17:0>";
3"M_L_MA<17:0>";
4"M_L_BA<1:0>";
5"M_L_BG<1:0>";
6"M_L_CKE<3:0>";
7"M_L_CS_N<7:0>";
8"M_L_ODT<3:0>";
9"M_L_DQ<63:0>";
10"M_L_CLK_DN<3:0>";
11"M_L_CLK_DP<3:0>";
12"M_L_ECC<7:0>";
13"M_L_C<2>";
14"M_L_ECC<0>";
15"M_L_ECC<1>";
16"M_L_ECC<2>";
17"M_L_ECC<3>";
18"M_L_ECC<4>";
19"M_L_ECC<5>";
20"M_L_ECC<6>";
21"M_L_ECC<7>";
22"M_L_DQ<0>";
23"M_L_DQ<1>";
24"M_L_DQ<2>";
25"M_L_DQ<3>";
26"M_L_DQ<4>";
27"M_L_DQ<5>";
28"M_L_DQ<6>";
29"M_L_DQ<7>";
30"M_L_DQ<8>";
31"M_L_DQ<9>";
32"M_L_DQ<10>";
33"M_L_CLK_DP<0>";
34"M_L_CLK_DP<1>";
35"M_L_CLK_DP<2>";
36"M_L_CLK_DP<3>";
37"M_L_CLK_DN<0>";
38"M_L_CLK_DN<1>";
39"M_L_CLK_DN<2>";
40"M_L_CLK_DN<3>";
41"M_L_DQ<11>";
42"M_L_DQ<12>";
43"M_L_DQ<13>";
44"M_L_DQ<14>";
45"M_L_DQ<15>";
46"M_L_DQ<16>";
47"M_L_DQ<17>";
48"M_L_DQ<18>";
49"M_L_DQ<19>";
50"M_L_DQ<20>";
51"M_L_DQ<21>";
52"M_L_DQ<22>";
53"M_L_DQ<23>";
54"M_L_DQ<24>";
55"M_L_DQ<25>";
56"M_L_DQ<26>";
57"M_L_DQ<27>";
58"M_L_DQ<28>";
59"M_L_DQ<29>";
60"M_L_DQ<30>";
61"M_L_DQ<31>";
62"M_L_DQ<32>";
63"M_L_DQ<33>";
64"M_L_DQ<34>";
65"M_L_DQ<35>";
66"M_L_DQ<36>";
67"M_L_DQ<37>";
68"M_L_DQ<38>";
69"M_L_DQ<39>";
70"M_L_DQ<40>";
71"M_L_DQ<41>";
72"M_L_DQ<42>";
73"M_L_DQ<43>";
74"M_L_DQ<44>";
75"M_L_DQ<45>";
76"M_L_DQ<46>";
77"M_L_DQ<47>";
78"M_L_DQ<48>";
79"M_L_DQ<49>";
80"M_L_DQ<50>";
81"M_L_DQ<51>";
82"M_L_DQ<52>";
83"M_L_DQ<53>";
84"M_L_DQ<54>";
85"M_L_DQ<55>";
86"M_L_DQ<56>";
87"M_L_DQ<57>";
88"M_L_DQ<58>";
89"M_L_DQ<59>";
90"M_L_DQ<60>";
91"M_L_DQ<61>";
92"M_L_DQ<62>";
93"M_L_DQ<63>";
94"M_L_ODT<0>";
95"M_L_ODT<1>";
96"M_L_ODT<2>";
97"M_L_ODT<3>";
98"M_L_MA<0>";
99"M_L_MA<1>";
100"M_L_MA<2>";
101"M_L_CS_N<0>";
102"M_L_CS_N<1>";
103"M_L_CS_N<2>";
104"M_L_CS_N<3>";
105"M_L_CS_N<4>";
106"M_L_CS_N<5>";
107"M_L_CS_N<6>";
108"M_L_CS_N<7>";
109"M_L_CKE<0>";
110"M_L_CKE<1>";
111"M_L_CKE<2>";
112"M_L_CKE<3>";
113"M_L_BG<0>";
114"M_L_BG<1>";
115"M_L_BA<0>";
116"M_L_BA<1>";
117"M_L_MA<3>";
118"M_L_MA<4>";
119"M_L_MA<5>";
120"M_L_MA<6>";
121"M_L_MA<7>";
122"M_L_MA<8>";
123"M_L_MA<9>";
124"M_L_MA<10>";
125"M_L_MA<11>";
126"M_L_MA<12>";
127"M_L_MA<13>";
128"M_L_MA<14>";
129"M_L_MA<15>";
130"M_L_MA<16>";
131"M_L_MA<17>";
132"M_L_DQS_DP<0>";
133"M_L_DQS_DP<1>";
134"M_L_DQS_DP<2>";
135"M_L_DQS_DP<3>";
136"M_L_DQS_DP<4>";
137"M_L_DQS_DP<5>";
138"M_L_DQS_DN<0>";
139"M_L_DQS_DN<1>";
140"M_L_DQS_DN<2>";
141"M_L_DQS_DN<3>";
142"M_L_DQS_DN<4>";
143"M_L_DQS_DN<5>";
144"M_L_DQS_DN<6>";
145"M_L_DQS_DN<7>";
146"M_L_DQS_DN<8>";
147"M_L_DQS_DN<9>";
148"M_L_DQS_DN<10>";
149"M_L_DQS_DN<11>";
150"M_L_DQS_DN<12>";
151"M_L_DQS_DN<13>";
152"M_L_DQS_DN<14>";
153"M_L_DQS_DN<15>";
154"M_L_DQS_DN<16>";
155"M_L_DQS_DN<17>";
156"M_L_PAR";
157"M_L_ALERT_N";
158"M_L_ACT_N";
159"M_L_DQS_DP<6>";
160"M_L_DQS_DP<7>";
161"M_L_DQS_DP<8>";
162"M_L_DQS_DP<9>";
163"M_L_DQS_DP<10>";
164"M_L_DQS_DP<11>";
165"M_L_DQS_DP<12>";
166"M_L_DQS_DP<13>";
167"M_L_DQS_DP<14>";
168"M_L_DQS_DP<15>";
169"M_L_DQS_DP<16>";
170"M_L_DQS_DP<17>";
%"TAP"
"6","(-5575,825)","0","mstr_standard","I10";
;
HDL_TAP"TRUE"
BODY_TYPE"PLUMBING"
CDS_LIB"mstr_standard";
"B \NAC \NWC"11;
"S \NAC"
BN"0"33;
%"TAP"
"6","(-2850,1575)","2","mstr_standard","I100";
;
HDL_TAP"TRUE"
BODY_TYPE"PLUMBING"
CDS_LIB"mstr_standard";
"B \NAC \NWC"8;
"S \NAC"
BN"3"97;
%"TAP"
"6","(-2850,1525)","2","mstr_standard","I101";
;
HDL_TAP"TRUE"
BODY_TYPE"PLUMBING"
CDS_LIB"mstr_standard";
"B \NAC \NWC"8;
"S \NAC"
BN"2"96;
%"TAP"
"6","(-2850,1475)","2","mstr_standard","I102";
;
HDL_TAP"TRUE"
BODY_TYPE"PLUMBING"
CDS_LIB"mstr_standard";
"B \NAC \NWC"8;
"S \NAC"
BN"1"95;
%"TAP"
"6","(-2850,1675)","2","mstr_standard","I103";
;
HDL_TAP"TRUE"
BODY_TYPE"PLUMBING"
CDS_LIB"mstr_standard";
"B \NAC \NWC"6;
"S \NAC"
BN"0"109;
%"TAP"
"6","(-2850,1725)","2","mstr_standard","I104";
;
HDL_TAP"TRUE"
BODY_TYPE"PLUMBING"
CDS_LIB"mstr_standard";
"B \NAC \NWC"6;
"S \NAC"
BN"1"110;
%"TAP"
"6","(-2850,1775)","2","mstr_standard","I105";
;
HDL_TAP"TRUE"
BODY_TYPE"PLUMBING"
CDS_LIB"mstr_standard";
"B \NAC \NWC"6;
"S \NAC"
BN"2"111;
%"TAP"
"6","(-2850,1825)","2","mstr_standard","I106";
;
HDL_TAP"TRUE"
BODY_TYPE"PLUMBING"
CDS_LIB"mstr_standard";
"B \NAC \NWC"6;
"S \NAC"
BN"3"112;
%"TAP"
"6","(-2850,1925)","2","mstr_standard","I107";
;
HDL_TAP"TRUE"
BODY_TYPE"PLUMBING"
CDS_LIB"mstr_standard";
"B \NAC \NWC"3;
"S \NAC"
BN"0"98;
%"TAP"
"6","(-2850,1975)","2","mstr_standard","I108";
;
HDL_TAP"TRUE"
BODY_TYPE"PLUMBING"
CDS_LIB"mstr_standard";
"B \NAC \NWC"3;
"S \NAC"
BN"1"99;
%"TAP"
"6","(-2850,2075)","2","mstr_standard","I109";
;
HDL_TAP"TRUE"
BODY_TYPE"PLUMBING"
CDS_LIB"mstr_standard";
"B \NAC \NWC"3;
"S \NAC"
BN"3"117;
%"TAP"
"6","(-5575,925)","0","mstr_standard","I11";
;
HDL_TAP"TRUE"
BODY_TYPE"PLUMBING"
CDS_LIB"mstr_standard";
"B \NAC \NWC"11;
"S \NAC"
BN"2"35;
%"TAP"
"6","(-2850,2025)","2","mstr_standard","I110";
;
HDL_TAP"TRUE"
BODY_TYPE"PLUMBING"
CDS_LIB"mstr_standard";
"B \NAC \NWC"3;
"S \NAC"
BN"2"100;
%"TAP"
"6","(-2850,2125)","2","mstr_standard","I111";
;
HDL_TAP"TRUE"
BODY_TYPE"PLUMBING"
CDS_LIB"mstr_standard";
"B \NAC \NWC"3;
"S \NAC"
BN"4"118;
%"TAP"
"6","(-2850,2175)","2","mstr_standard","I112";
;
HDL_TAP"TRUE"
BODY_TYPE"PLUMBING"
CDS_LIB"mstr_standard";
"B \NAC \NWC"3;
"S \NAC"
BN"5"119;
%"TAP"
"6","(-2850,2225)","2","mstr_standard","I113";
;
HDL_TAP"TRUE"
BODY_TYPE"PLUMBING"
CDS_LIB"mstr_standard";
"B \NAC \NWC"3;
"S \NAC"
BN"6"120;
%"TAP"
"6","(-2850,2325)","2","mstr_standard","I114";
;
HDL_TAP"TRUE"
BODY_TYPE"PLUMBING"
CDS_LIB"mstr_standard";
"B \NAC \NWC"3;
"S \NAC"
BN"8"122;
%"TAP"
"6","(-2850,2275)","2","mstr_standard","I115";
;
HDL_TAP"TRUE"
BODY_TYPE"PLUMBING"
CDS_LIB"mstr_standard";
"B \NAC \NWC"3;
"S \NAC"
BN"7"121;
%"TAP"
"6","(-2850,2475)","2","mstr_standard","I116";
;
HDL_TAP"TRUE"
BODY_TYPE"PLUMBING"
CDS_LIB"mstr_standard";
"B \NAC \NWC"3;
"S \NAC"
BN"11"125;
%"TAP"
"6","(-2850,2425)","2","mstr_standard","I117";
;
HDL_TAP"TRUE"
BODY_TYPE"PLUMBING"
CDS_LIB"mstr_standard";
"B \NAC \NWC"3;
"S \NAC"
BN"10"124;
%"TAP"
"6","(-2850,2375)","2","mstr_standard","I118";
;
HDL_TAP"TRUE"
BODY_TYPE"PLUMBING"
CDS_LIB"mstr_standard";
"B \NAC \NWC"3;
"S \NAC"
BN"9"123;
%"TAP"
"6","(-2850,2525)","2","mstr_standard","I119";
;
HDL_TAP"TRUE"
BODY_TYPE"PLUMBING"
CDS_LIB"mstr_standard";
"B \NAC \NWC"3;
"S \NAC"
BN"12"126;
%"TAP"
"6","(-5575,975)","0","mstr_standard","I12";
;
HDL_TAP"TRUE"
BODY_TYPE"PLUMBING"
CDS_LIB"mstr_standard";
"B \NAC \NWC"11;
"S \NAC"
BN"3"36;
%"TAP"
"6","(-2850,2575)","2","mstr_standard","I120";
;
HDL_TAP"TRUE"
BODY_TYPE"PLUMBING"
CDS_LIB"mstr_standard";
"B \NAC \NWC"3;
"S \NAC"
BN"13"127;
%"TAP"
"6","(-2850,2625)","2","mstr_standard","I121";
;
HDL_TAP"TRUE"
BODY_TYPE"PLUMBING"
CDS_LIB"mstr_standard";
"B \NAC \NWC"3;
"S \NAC"
BN"14"128;
%"TAP"
"6","(-2850,2675)","2","mstr_standard","I122";
;
HDL_TAP"TRUE"
BODY_TYPE"PLUMBING"
CDS_LIB"mstr_standard";
"B \NAC \NWC"3;
"S \NAC"
BN"15"129;
%"TAP"
"6","(-2850,2725)","2","mstr_standard","I123";
;
HDL_TAP"TRUE"
BODY_TYPE"PLUMBING"
CDS_LIB"mstr_standard";
"B \NAC \NWC"3;
"S \NAC"
BN"16"130;
%"TAP"
"6","(-2850,2775)","2","mstr_standard","I124";
;
HDL_TAP"TRUE"
BODY_TYPE"PLUMBING"
CDS_LIB"mstr_standard";
"B \NAC \NWC"3;
"S \NAC"
BN"17"131;
%"TAP"
"6","(-2850,2925)","2","mstr_standard","I125";
;
HDL_TAP"TRUE"
BODY_TYPE"PLUMBING"
CDS_LIB"mstr_standard";
"B \NAC \NWC"2;
"S \NAC"
BN"1"139;
%"TAP"
"6","(-2850,2975)","2","mstr_standard","I126";
;
HDL_TAP"TRUE"
BODY_TYPE"PLUMBING"
CDS_LIB"mstr_standard";
"B \NAC \NWC"2;
"S \NAC"
BN"2"140;
%"TAP"
"6","(-2850,2875)","2","mstr_standard","I127";
;
HDL_TAP"TRUE"
BODY_TYPE"PLUMBING"
CDS_LIB"mstr_standard";
"B \NAC \NWC"2;
"S \NAC"
BN"0"138;
%"TAP"
"6","(-2850,3075)","2","mstr_standard","I128";
;
HDL_TAP"TRUE"
BODY_TYPE"PLUMBING"
CDS_LIB"mstr_standard";
"B \NAC \NWC"2;
"S \NAC"
BN"4"142;
%"TAP"
"6","(-2850,3025)","2","mstr_standard","I129";
;
HDL_TAP"TRUE"
BODY_TYPE"PLUMBING"
CDS_LIB"mstr_standard";
"B \NAC \NWC"2;
"S \NAC"
BN"3"141;
%"TAP"
"6","(-5575,1075)","0","mstr_standard","I13";
;
HDL_TAP"TRUE"
BODY_TYPE"PLUMBING"
CDS_LIB"mstr_standard";
"B \NAC \NWC"12;
"S \NAC"
BN"0"14;
%"TAP"
"6","(-2850,3125)","2","mstr_standard","I130";
;
HDL_TAP"TRUE"
BODY_TYPE"PLUMBING"
CDS_LIB"mstr_standard";
"B \NAC \NWC"2;
"S \NAC"
BN"5"143;
%"TAP"
"6","(-2850,3175)","2","mstr_standard","I131";
;
HDL_TAP"TRUE"
BODY_TYPE"PLUMBING"
CDS_LIB"mstr_standard";
"B \NAC \NWC"2;
"S \NAC"
BN"6"144;
%"TAP"
"6","(-2850,3225)","2","mstr_standard","I132";
;
HDL_TAP"TRUE"
BODY_TYPE"PLUMBING"
CDS_LIB"mstr_standard";
"B \NAC \NWC"2;
"S \NAC"
BN"7"145;
%"TAP"
"6","(-2850,3275)","2","mstr_standard","I133";
;
HDL_TAP"TRUE"
BODY_TYPE"PLUMBING"
CDS_LIB"mstr_standard";
"B \NAC \NWC"2;
"S \NAC"
BN"8"146;
%"TAP"
"6","(-2850,3325)","2","mstr_standard","I134";
;
HDL_TAP"TRUE"
BODY_TYPE"PLUMBING"
CDS_LIB"mstr_standard";
"B \NAC \NWC"2;
"S \NAC"
BN"9"147;
%"TAP"
"6","(-2850,3375)","2","mstr_standard","I135";
;
HDL_TAP"TRUE"
BODY_TYPE"PLUMBING"
CDS_LIB"mstr_standard";
"B \NAC \NWC"2;
"S \NAC"
BN"10"148;
%"TAP"
"6","(-2850,3475)","2","mstr_standard","I136";
;
HDL_TAP"TRUE"
BODY_TYPE"PLUMBING"
CDS_LIB"mstr_standard";
"B \NAC \NWC"2;
"S \NAC"
BN"12"150;
%"TAP"
"6","(-2850,3425)","2","mstr_standard","I137";
;
HDL_TAP"TRUE"
BODY_TYPE"PLUMBING"
CDS_LIB"mstr_standard";
"B \NAC \NWC"2;
"S \NAC"
BN"11"149;
%"TAP"
"6","(-2850,3625)","2","mstr_standard","I138";
;
HDL_TAP"TRUE"
BODY_TYPE"PLUMBING"
CDS_LIB"mstr_standard";
"B \NAC \NWC"2;
"S \NAC"
BN"15"153;
%"TAP"
"6","(-2850,3575)","2","mstr_standard","I139";
;
HDL_TAP"TRUE"
BODY_TYPE"PLUMBING"
CDS_LIB"mstr_standard";
"B \NAC \NWC"2;
"S \NAC"
BN"14"152;
%"TAP"
"6","(-5575,1125)","0","mstr_standard","I14";
;
HDL_TAP"TRUE"
BODY_TYPE"PLUMBING"
CDS_LIB"mstr_standard";
"B \NAC \NWC"12;
"S \NAC"
BN"1"15;
%"TAP"
"6","(-2850,3525)","2","mstr_standard","I140";
;
HDL_TAP"TRUE"
BODY_TYPE"PLUMBING"
CDS_LIB"mstr_standard";
"B \NAC \NWC"2;
"S \NAC"
BN"13"151;
%"TAP"
"6","(-2850,3675)","2","mstr_standard","I141";
;
HDL_TAP"TRUE"
BODY_TYPE"PLUMBING"
CDS_LIB"mstr_standard";
"B \NAC \NWC"2;
"S \NAC"
BN"16"154;
%"TAP"
"6","(-2850,3725)","2","mstr_standard","I142";
;
HDL_TAP"TRUE"
BODY_TYPE"PLUMBING"
CDS_LIB"mstr_standard";
"B \NAC \NWC"2;
"S \NAC"
BN"17"155;
%"TAP"
"6","(-2850,3825)","2","mstr_standard","I143";
;
HDL_TAP"TRUE"
BODY_TYPE"PLUMBING"
CDS_LIB"mstr_standard";
"B \NAC \NWC"1;
"S \NAC"
BN"0"132;
%"TAP"
"6","(-2850,3875)","2","mstr_standard","I144";
;
HDL_TAP"TRUE"
BODY_TYPE"PLUMBING"
CDS_LIB"mstr_standard";
"B \NAC \NWC"1;
"S \NAC"
BN"1"133;
%"TAP"
"6","(-2850,3925)","2","mstr_standard","I145";
;
HDL_TAP"TRUE"
BODY_TYPE"PLUMBING"
CDS_LIB"mstr_standard";
"B \NAC \NWC"1;
"S \NAC"
BN"2"134;
%"TAP"
"6","(-2850,3975)","2","mstr_standard","I146";
;
HDL_TAP"TRUE"
BODY_TYPE"PLUMBING"
CDS_LIB"mstr_standard";
"B \NAC \NWC"1;
"S \NAC"
BN"3"135;
%"TAP"
"6","(-5575,1175)","0","mstr_standard","I15";
;
HDL_TAP"TRUE"
BODY_TYPE"PLUMBING"
CDS_LIB"mstr_standard";
"B \NAC \NWC"12;
"S \NAC"
BN"2"16;
%"TAP"
"6","(-2850,4025)","2","mstr_standard","I157";
;
HDL_TAP"TRUE"
BODY_TYPE"PLUMBING"
CDS_LIB"mstr_standard";
"B \NAC \NWC"1;
"S \NAC"
BN"4"136;
%"TAP"
"6","(-2850,4125)","2","mstr_standard","I158";
;
HDL_TAP"TRUE"
BODY_TYPE"PLUMBING"
CDS_LIB"mstr_standard";
"B \NAC \NWC"1;
"S \NAC"
BN"6"159;
%"TAP"
"6","(-2850,4075)","2","mstr_standard","I159";
;
HDL_TAP"TRUE"
BODY_TYPE"PLUMBING"
CDS_LIB"mstr_standard";
"B \NAC \NWC"1;
"S \NAC"
BN"5"137;
%"TAP"
"6","(-5575,1275)","0","mstr_standard","I16";
;
HDL_TAP"TRUE"
BODY_TYPE"PLUMBING"
CDS_LIB"mstr_standard";
"B \NAC \NWC"12;
"S \NAC"
BN"4"18;
%"TAP"
"6","(-2850,4175)","2","mstr_standard","I160";
;
HDL_TAP"TRUE"
BODY_TYPE"PLUMBING"
CDS_LIB"mstr_standard";
"B \NAC \NWC"1;
"S \NAC"
BN"7"160;
%"TAP"
"6","(-2850,4225)","2","mstr_standard","I161";
;
HDL_TAP"TRUE"
BODY_TYPE"PLUMBING"
CDS_LIB"mstr_standard";
"B \NAC \NWC"1;
"S \NAC"
BN"8"161;
%"TAP"
"6","(-2850,4275)","2","mstr_standard","I162";
;
HDL_TAP"TRUE"
BODY_TYPE"PLUMBING"
CDS_LIB"mstr_standard";
"B \NAC \NWC"1;
"S \NAC"
BN"9"162;
%"TAP"
"6","(-2850,4325)","2","mstr_standard","I163";
;
HDL_TAP"TRUE"
BODY_TYPE"PLUMBING"
CDS_LIB"mstr_standard";
"B \NAC \NWC"1;
"S \NAC"
BN"10"163;
%"TAP"
"6","(-2850,4375)","2","mstr_standard","I164";
;
HDL_TAP"TRUE"
BODY_TYPE"PLUMBING"
CDS_LIB"mstr_standard";
"B \NAC \NWC"1;
"S \NAC"
BN"11"164;
%"TAP"
"6","(-2850,4525)","2","mstr_standard","I165";
;
HDL_TAP"TRUE"
BODY_TYPE"PLUMBING"
CDS_LIB"mstr_standard";
"B \NAC \NWC"1;
"S \NAC"
BN"14"167;
%"TAP"
"6","(-2850,4475)","2","mstr_standard","I166";
;
HDL_TAP"TRUE"
BODY_TYPE"PLUMBING"
CDS_LIB"mstr_standard";
"B \NAC \NWC"1;
"S \NAC"
BN"13"166;
%"TAP"
"6","(-2850,4425)","2","mstr_standard","I167";
;
HDL_TAP"TRUE"
BODY_TYPE"PLUMBING"
CDS_LIB"mstr_standard";
"B \NAC \NWC"1;
"S \NAC"
BN"12"165;
%"TAP"
"6","(-2850,4575)","2","mstr_standard","I168";
;
HDL_TAP"TRUE"
BODY_TYPE"PLUMBING"
CDS_LIB"mstr_standard";
"B \NAC \NWC"1;
"S \NAC"
BN"15"168;
%"TAP"
"6","(-2850,4625)","2","mstr_standard","I169";
;
HDL_TAP"TRUE"
BODY_TYPE"PLUMBING"
CDS_LIB"mstr_standard";
"B \NAC \NWC"1;
"S \NAC"
BN"16"169;
%"TAP"
"6","(-5575,1225)","0","mstr_standard","I17";
;
HDL_TAP"TRUE"
BODY_TYPE"PLUMBING"
CDS_LIB"mstr_standard";
"B \NAC \NWC"12;
"S \NAC"
BN"3"17;
%"TAP"
"6","(-2850,4675)","2","mstr_standard","I170";
;
HDL_TAP"TRUE"
BODY_TYPE"PLUMBING"
CDS_LIB"mstr_standard";
"B \NAC \NWC"1;
"S \NAC"
BN"17"170;
%"SKX_EXT_B"
"7","(-4175,2575)","0","chpset_lib","I172";
;
CDS_SEC"7"
CDS_LOCATION"U2D1"
SEC"7"
CDS_LIB"chpset_lib"
SEC_TYPE"BGA1"
PACK_TYPE"BGA1"
MATERIAL"IC"
PART_NUMBER"TBD"
LOCATION"U2D1";
"DDR4_PAR"
$PN"DV53"156;
"DDR4_ODT<0>"
$PN"DR50"94;
"DDR4_ODT<1>"
$PN"DN48"95;
"DDR4_ODT<2>"
$PN"DT49"96;
"DDR4_ODT<3>"
$PN"DM47"97;
"DDR4_MA<0>"
$PN"DW52"98;
"DDR4_MA<1>"
$PN"DW58"99;
"DDR4_MA<2>"
$PN"DV57"100;
"DDR4_MA<3>"
$PN"DR58"117;
"DDR4_MA<4>"
$PN"DT59"118;
"DDR4_MA<5>"
$PN"DN58"119;
"DDR4_MA<6>"
$PN"DM59"120;
"DDR4_MA<7>"
$PN"DK61"121;
"DDR4_MA<8>"
$PN"DJ60"122;
"DDR4_MA<9>"
$PN"DV59"123;
"DDR4_MA<10>"
$PN"DT55"124;
"DDR4_MA<11>"
$PN"DR60"125;
"DDR4_MA<12>"
$PN"DN60"126;
"DDR4_MA<13>"
$PN"DT51"127;
"DDR4_MA<14>"
$PN"DM51"128;
"DDR4_MA<15>"
$PN"DR52"129;
"DDR4_MA<16>"
$PN"DN52"130;
"DDR4_MA<17>"
$PN"DR48"131;
"DDR4_ECC<0>"
$PN"DY69"14;
"DDR4_ECC<1>"
$PN"EA68"15;
"DDR4_ECC<2>"
$PN"DV65"16;
"DDR4_ECC<3>"
$PN"DY65"17;
"DDR4_ECC<4>"
$PN"DU68"18;
"DDR4_ECC<5>"
$PN"DV69"19;
"DDR4_ECC<6>"
$PN"DU66"20;
"DDR4_ECC<7>"
$PN"EA66"21;
"DDR4_DQS_DP<0>"
$PN"CM81"132;
"DDR4_DQS_DP<1>"
$PN"DB81"133;
"DDR4_DQS_DP<2>"
$PN"EB79"134;
"DDR4_DQS_DP<3>"
$PN"ED73"135;
"DDR4_DQS_DP<4>"
$PN"DT41"136;
"DDR4_DQS_DP<5>"
$PN"EC32"137;
"DDR4_DQS_DP<6>"
$PN"EC26"159;
"DDR4_DQS_DP<7>"
$PN"DJ26"160;
"DDR4_DQS_DP<8>"
$PN"DY67"161;
"DDR4_DQS_DP<9>"
$PN"CP79"162;
"DDR4_DQS_DP<10>"
$PN"DD79"163;
"DDR4_DQS_DP<11>"
$PN"DV79"164;
"DDR4_DQS_DP<12>"
$PN"DY73"165;
"DDR4_DQS_DP<13>"
$PN"DM41"166;
"DDR4_DQS_DP<14>"
$PN"DW32"167;
"DDR4_DQS_DP<15>"
$PN"DW26"168;
"DDR4_DQS_DP<16>"
$PN"DE26"169;
"DDR4_DQS_DP<17>"
$PN"DT67"170;
"DDR4_DQS_DN<0>"
$PN"CL82"138;
"DDR4_DQS_DN<1>"
$PN"DA82"139;
"DDR4_DQS_DN<2>"
$PN"ED79"140;
"DDR4_DQS_DN<3>"
$PN"EF73"141;
"DDR4_DQS_DN<4>"
$PN"DV41"142;
"DDR4_DQS_DN<5>"
$PN"EE32"143;
"DDR4_DQS_DN<6>"
$PN"EE26"144;
"DDR4_DQS_DN<7>"
$PN"DL26"145;
"DDR4_DQS_DN<8>"
$PN"EB67"146;
"DDR4_DQS_DN<9>"
$PN"CN80"147;
"DDR4_DQS_DN<10>"
$PN"DC80"148;
"DDR4_DQS_DN<11>"
$PN"DY79"149;
"DDR4_DQS_DN<12>"
$PN"EB73"150;
"DDR4_DQS_DN<13>"
$PN"DP41"151;
"DDR4_DQS_DN<14>"
$PN"EA32"152;
"DDR4_DQS_DN<15>"
$PN"EA26"153;
"DDR4_DQS_DN<16>"
$PN"DG26"154;
"DDR4_DQS_DN<17>"
$PN"DV67"155;
"DDR4_DQ<0>"
$PN"CM79"22;
"DDR4_DQ<1>"
$PN"CK81"23;
"DDR4_DQ<2>"
$PN"CT81"24;
"DDR4_DQ<3>"
$PN"CR82"25;
"DDR4_DQ<4>"
$PN"CK79"26;
"DDR4_DQ<5>"
$PN"CJ80"27;
"DDR4_DQ<6>"
$PN"CR80"28;
"DDR4_DQ<7>"
$PN"CN82"29;
"DDR4_DQ<8>"
$PN"DB79"30;
"DDR4_DQ<9>"
$PN"CY81"31;
"DDR4_DQ<10>"
$PN"DE80"32;
"DDR4_DQ<11>"
$PN"DF81"41;
"DDR4_DQ<12>"
$PN"CY79"42;
"DDR4_DQ<13>"
$PN"CW80"43;
"DDR4_DQ<14>"
$PN"DC82"44;
"DDR4_DQ<15>"
$PN"DE82"45;
"DDR4_DQ<16>"
$PN"DW80"46;
"DDR4_DQ<17>"
$PN"EC80"47;
"DDR4_DQ<18>"
$PN"DY77"48;
"DDR4_DQ<19>"
$PN"EB77"49;
"DDR4_DQ<20>"
$PN"DY81"50;
"DDR4_DQ<21>"
$PN"EB81"51;
"DDR4_DQ<22>"
$PN"DW78"52;
"DDR4_DQ<23>"
$PN"EC78"53;
"DDR4_DQ<24>"
$PN"ED75"54;
"DDR4_DQ<25>"
$PN"EE74"55;
"DDR4_DQ<26>"
$PN"EB71"56;
"DDR4_DQ<27>"
$PN"ED71"57;
"DDR4_DQ<28>"
$PN"EA74"58;
"DDR4_DQ<29>"
$PN"EB75"59;
"DDR4_DQ<30>"
$PN"EA72"60;
"DDR4_DQ<31>"
$PN"EE72"61;
"DDR4_DQ<32>"
$PN"DU42"62;
"DDR4_DQ<33>"
$PN"DW42"63;
"DDR4_DQ<34>"
$PN"DP39"64;
"DDR4_DQ<35>"
$PN"DT39"65;
"DDR4_DQ<36>"
$PN"DL42"66;
"DDR4_DQ<37>"
$PN"DN42"67;
"DDR4_DQ<38>"
$PN"DN40"68;
"DDR4_DQ<39>"
$PN"DU40"69;
"DDR4_DQ<40>"
$PN"EC34"70;
"DDR4_DQ<41>"
$PN"ED33"71;
"DDR4_DQ<42>"
$PN"EA30"72;
"DDR4_DQ<43>"
$PN"EC30"73;
"DDR4_DQ<44>"
$PN"DY33"74;
"DDR4_DQ<45>"
$PN"EA34"75;
"DDR4_DQ<46>"
$PN"DY31"76;
"DDR4_DQ<47>"
$PN"ED31"77;
"DDR4_DQ<48>"
$PN"EC28"78;
"DDR4_DQ<49>"
$PN"ED27"79;
"DDR4_DQ<50>"
$PN"EA24"80;
"DDR4_DQ<51>"
$PN"EC24"81;
"DDR4_DQ<52>"
$PN"DY27"82;
"DDR4_DQ<53>"
$PN"EA28"83;
"DDR4_DQ<54>"
$PN"DY25"84;
"DDR4_DQ<55>"
$PN"ED25"85;
"DDR4_DQ<56>"
$PN"DF27"86;
"DDR4_DQ<57>"
$PN"DK27"87;
"DDR4_DQ<58>"
$PN"DD25"88;
"DDR4_DQ<59>"
$PN"DJ24"89;
"DDR4_DQ<60>"
$PN"DG28"90;
"DDR4_DQ<61>"
$PN"DJ28"91;
"DDR4_DQ<62>"
$PN"DF25"92;
"DDR4_DQ<63>"
$PN"DK25"93;
"DDR4_CS_N<0>"
$PN"DV51"101;
"DDR4_CS_N<1>"
$PN"DN50"102;
"DDR4_CS_N<2>"
$PN"DR46"103;
"DDR4_CS_N<3>"
$PN"DK47"104;
"DDR4_CS_N<4>"
$PN"DW50"105;
"DDR4_CS_N<5>"
$PN"DM49"106;
"DDR4_CS_N<6>"
$PN"DT45"107;
"DDR4_CS_N<7>"
$PN"DN46"108;
"DDR4_CLK_DP<0>"
$PN"DN54"33;
"DDR4_CLK_DP<1>"
$PN"DT53"34;
"DDR4_CLK_DP<2>"
$PN"DN56"35;
"DDR4_CLK_DP<3>"
$PN"DR56"36;
"DDR4_CLK_DN<0>"
$PN"DM55"37;
"DDR4_CLK_DN<1>"
$PN"DR54"38;
"DDR4_CLK_DN<2>"
$PN"DM57"39;
"DDR4_CLK_DN<3>"
$PN"DT57"40;
"DDR4_CKE<0>"
$PN"DM63"109;
"DDR4_CKE<1>"
$PN"DN64"110;
"DDR4_CKE<2>"
$PN"DL64"111;
"DDR4_CKE<3>"
$PN"DR64"112;
"DDR4_CID<2>"
$PN"DT47"13;
"DDR4_BG<0>"
$PN"DJ62"113;
"DDR4_BG<1>"
$PN"DM61"114;
"DDR4_BA<0>"
$PN"DM53"115;
"DDR4_BA<1>"
$PN"DV55"116;
"DDR4_ALERT_N"
$PN"DT61"157;
"DDR4_ACT_N"
$PN"DR62"158;
%"TAP"
"6","(-5575,1325)","0","mstr_standard","I18";
;
HDL_TAP"TRUE"
BODY_TYPE"PLUMBING"
CDS_LIB"mstr_standard";
"B \NAC \NWC"12;
"S \NAC"
BN"5"19;
%"TAP"
"6","(-5575,1375)","0","mstr_standard","I19";
;
HDL_TAP"TRUE"
BODY_TYPE"PLUMBING"
CDS_LIB"mstr_standard";
"B \NAC \NWC"12;
"S \NAC"
BN"6"20;
%"TAP"
"6","(-5575,1425)","0","mstr_standard","I20";
;
HDL_TAP"TRUE"
BODY_TYPE"PLUMBING"
CDS_LIB"mstr_standard";
"B \NAC \NWC"12;
"S \NAC"
BN"7"21;
%"TAP"
"6","(-5575,1525)","0","mstr_standard","I21";
;
HDL_TAP"TRUE"
BODY_TYPE"PLUMBING"
CDS_LIB"mstr_standard";
"B \NAC \NWC"9;
"S \NAC"
BN"0"22;
%"TAP"
"6","(-5575,1575)","0","mstr_standard","I22";
;
HDL_TAP"TRUE"
BODY_TYPE"PLUMBING"
CDS_LIB"mstr_standard";
"B \NAC \NWC"9;
"S \NAC"
BN"1"23;
%"TAP"
"6","(-5575,1625)","0","mstr_standard","I23";
;
HDL_TAP"TRUE"
BODY_TYPE"PLUMBING"
CDS_LIB"mstr_standard";
"B \NAC \NWC"9;
"S \NAC"
BN"2"24;
%"TAP"
"6","(-5575,1675)","0","mstr_standard","I24";
;
HDL_TAP"TRUE"
BODY_TYPE"PLUMBING"
CDS_LIB"mstr_standard";
"B \NAC \NWC"9;
"S \NAC"
BN"3"25;
%"TAP"
"6","(-5575,1725)","0","mstr_standard","I25";
;
HDL_TAP"TRUE"
BODY_TYPE"PLUMBING"
CDS_LIB"mstr_standard";
"B \NAC \NWC"9;
"S \NAC"
BN"4"26;
%"TAP"
"6","(-5575,1775)","0","mstr_standard","I26";
;
HDL_TAP"TRUE"
BODY_TYPE"PLUMBING"
CDS_LIB"mstr_standard";
"B \NAC \NWC"9;
"S \NAC"
BN"5"27;
%"TAP"
"6","(-5575,1825)","0","mstr_standard","I27";
;
HDL_TAP"TRUE"
BODY_TYPE"PLUMBING"
CDS_LIB"mstr_standard";
"B \NAC \NWC"9;
"S \NAC"
BN"6"28;
%"TAP"
"6","(-5575,1925)","0","mstr_standard","I28";
;
HDL_TAP"TRUE"
BODY_TYPE"PLUMBING"
CDS_LIB"mstr_standard";
"B \NAC \NWC"9;
"S \NAC"
BN"8"30;
%"TAP"
"6","(-5575,1875)","0","mstr_standard","I29";
;
HDL_TAP"TRUE"
BODY_TYPE"PLUMBING"
CDS_LIB"mstr_standard";
"B \NAC \NWC"9;
"S \NAC"
BN"7"29;
%"TAP"
"6","(-5575,1975)","0","mstr_standard","I31";
;
HDL_TAP"TRUE"
BODY_TYPE"PLUMBING"
CDS_LIB"mstr_standard";
"B \NAC \NWC"9;
"S \NAC"
BN"9"31;
%"TAP"
"6","(-5575,2025)","0","mstr_standard","I32";
;
HDL_TAP"TRUE"
BODY_TYPE"PLUMBING"
CDS_LIB"mstr_standard";
"B \NAC \NWC"9;
"S \NAC"
BN"10"32;
%"TAP"
"6","(-5575,2075)","0","mstr_standard","I33";
;
HDL_TAP"TRUE"
BODY_TYPE"PLUMBING"
CDS_LIB"mstr_standard";
"B \NAC \NWC"9;
"S \NAC"
BN"11"41;
%"TAP"
"6","(-5575,2125)","0","mstr_standard","I34";
;
HDL_TAP"TRUE"
BODY_TYPE"PLUMBING"
CDS_LIB"mstr_standard";
"B \NAC \NWC"9;
"S \NAC"
BN"12"42;
%"TAP"
"6","(-5575,2175)","0","mstr_standard","I35";
;
HDL_TAP"TRUE"
BODY_TYPE"PLUMBING"
CDS_LIB"mstr_standard";
"B \NAC \NWC"9;
"S \NAC"
BN"13"43;
%"TAP"
"6","(-5575,2225)","0","mstr_standard","I36";
;
HDL_TAP"TRUE"
BODY_TYPE"PLUMBING"
CDS_LIB"mstr_standard";
"B \NAC \NWC"9;
"S \NAC"
BN"14"44;
%"TAP"
"6","(-5575,2275)","0","mstr_standard","I37";
;
HDL_TAP"TRUE"
BODY_TYPE"PLUMBING"
CDS_LIB"mstr_standard";
"B \NAC \NWC"9;
"S \NAC"
BN"15"45;
%"TAP"
"6","(-5575,2325)","0","mstr_standard","I38";
;
HDL_TAP"TRUE"
BODY_TYPE"PLUMBING"
CDS_LIB"mstr_standard";
"B \NAC \NWC"9;
"S \NAC"
BN"16"46;
%"TAP"
"6","(-5575,2375)","0","mstr_standard","I39";
;
HDL_TAP"TRUE"
BODY_TYPE"PLUMBING"
CDS_LIB"mstr_standard";
"B \NAC \NWC"9;
"S \NAC"
BN"17"47;
%"TAP"
"6","(-5575,2425)","0","mstr_standard","I40";
;
HDL_TAP"TRUE"
BODY_TYPE"PLUMBING"
CDS_LIB"mstr_standard";
"B \NAC \NWC"9;
"S \NAC"
BN"18"48;
%"TAP"
"6","(-5575,2475)","0","mstr_standard","I41";
;
HDL_TAP"TRUE"
BODY_TYPE"PLUMBING"
CDS_LIB"mstr_standard";
"B \NAC \NWC"9;
"S \NAC"
BN"19"49;
%"TAP"
"6","(-5575,2525)","0","mstr_standard","I42";
;
HDL_TAP"TRUE"
BODY_TYPE"PLUMBING"
CDS_LIB"mstr_standard";
"B \NAC \NWC"9;
"S \NAC"
BN"20"50;
%"TAP"
"6","(-5575,2575)","0","mstr_standard","I43";
;
HDL_TAP"TRUE"
BODY_TYPE"PLUMBING"
CDS_LIB"mstr_standard";
"B \NAC \NWC"9;
"S \NAC"
BN"21"51;
%"TAP"
"6","(-5575,2625)","0","mstr_standard","I44";
;
HDL_TAP"TRUE"
BODY_TYPE"PLUMBING"
CDS_LIB"mstr_standard";
"B \NAC \NWC"9;
"S \NAC"
BN"22"52;
%"TAP"
"6","(-5575,2675)","0","mstr_standard","I45";
;
HDL_TAP"TRUE"
BODY_TYPE"PLUMBING"
CDS_LIB"mstr_standard";
"B \NAC \NWC"9;
"S \NAC"
BN"23"53;
%"TAP"
"6","(-5575,2725)","0","mstr_standard","I46";
;
HDL_TAP"TRUE"
BODY_TYPE"PLUMBING"
CDS_LIB"mstr_standard";
"B \NAC \NWC"9;
"S \NAC"
BN"24"54;
%"TAP"
"6","(-5575,2825)","0","mstr_standard","I47";
;
HDL_TAP"TRUE"
BODY_TYPE"PLUMBING"
CDS_LIB"mstr_standard";
"B \NAC \NWC"9;
"S \NAC"
BN"26"56;
%"TAP"
"6","(-5575,2775)","0","mstr_standard","I48";
;
HDL_TAP"TRUE"
BODY_TYPE"PLUMBING"
CDS_LIB"mstr_standard";
"B \NAC \NWC"9;
"S \NAC"
BN"25"55;
%"TAP"
"6","(-5575,2875)","0","mstr_standard","I49";
;
HDL_TAP"TRUE"
BODY_TYPE"PLUMBING"
CDS_LIB"mstr_standard";
"B \NAC \NWC"9;
"S \NAC"
BN"27"57;
%"TAP"
"6","(-5575,625)","0","mstr_standard","I5";
;
HDL_TAP"TRUE"
BODY_TYPE"PLUMBING"
CDS_LIB"mstr_standard";
"B \NAC \NWC"10;
"S \NAC"
BN"0"37;
%"TAP"
"6","(-5575,2925)","0","mstr_standard","I50";
;
HDL_TAP"TRUE"
BODY_TYPE"PLUMBING"
CDS_LIB"mstr_standard";
"B \NAC \NWC"9;
"S \NAC"
BN"28"58;
%"TAP"
"6","(-5575,2975)","0","mstr_standard","I51";
;
HDL_TAP"TRUE"
BODY_TYPE"PLUMBING"
CDS_LIB"mstr_standard";
"B \NAC \NWC"9;
"S \NAC"
BN"29"59;
%"TAP"
"6","(-5575,3075)","0","mstr_standard","I52";
;
HDL_TAP"TRUE"
BODY_TYPE"PLUMBING"
CDS_LIB"mstr_standard";
"B \NAC \NWC"9;
"S \NAC"
BN"31"61;
%"TAP"
"6","(-5575,3025)","0","mstr_standard","I53";
;
HDL_TAP"TRUE"
BODY_TYPE"PLUMBING"
CDS_LIB"mstr_standard";
"B \NAC \NWC"9;
"S \NAC"
BN"30"60;
%"TAP"
"6","(-5575,3125)","0","mstr_standard","I54";
;
HDL_TAP"TRUE"
BODY_TYPE"PLUMBING"
CDS_LIB"mstr_standard";
"B \NAC \NWC"9;
"S \NAC"
BN"32"62;
%"TAP"
"6","(-5575,3175)","0","mstr_standard","I55";
;
HDL_TAP"TRUE"
BODY_TYPE"PLUMBING"
CDS_LIB"mstr_standard";
"B \NAC \NWC"9;
"S \NAC"
BN"33"63;
%"TAP"
"6","(-5575,3225)","0","mstr_standard","I56";
;
HDL_TAP"TRUE"
BODY_TYPE"PLUMBING"
CDS_LIB"mstr_standard";
"B \NAC \NWC"9;
"S \NAC"
BN"34"64;
%"TAP"
"6","(-5575,3325)","0","mstr_standard","I57";
;
HDL_TAP"TRUE"
BODY_TYPE"PLUMBING"
CDS_LIB"mstr_standard";
"B \NAC \NWC"9;
"S \NAC"
BN"36"66;
%"TAP"
"6","(-5575,3275)","0","mstr_standard","I58";
;
HDL_TAP"TRUE"
BODY_TYPE"PLUMBING"
CDS_LIB"mstr_standard";
"B \NAC \NWC"9;
"S \NAC"
BN"35"65;
%"TAP"
"6","(-5575,3375)","0","mstr_standard","I59";
;
HDL_TAP"TRUE"
BODY_TYPE"PLUMBING"
CDS_LIB"mstr_standard";
"B \NAC \NWC"9;
"S \NAC"
BN"37"67;
%"TAP"
"6","(-5575,675)","0","mstr_standard","I6";
;
HDL_TAP"TRUE"
BODY_TYPE"PLUMBING"
CDS_LIB"mstr_standard";
"B \NAC \NWC"10;
"S \NAC"
BN"1"38;
%"TAP"
"6","(-5575,3425)","0","mstr_standard","I60";
;
HDL_TAP"TRUE"
BODY_TYPE"PLUMBING"
CDS_LIB"mstr_standard";
"B \NAC \NWC"9;
"S \NAC"
BN"38"68;
%"TAP"
"6","(-5575,3475)","0","mstr_standard","I61";
;
HDL_TAP"TRUE"
BODY_TYPE"PLUMBING"
CDS_LIB"mstr_standard";
"B \NAC \NWC"9;
"S \NAC"
BN"39"69;
%"TAP"
"6","(-5575,3525)","0","mstr_standard","I62";
;
HDL_TAP"TRUE"
BODY_TYPE"PLUMBING"
CDS_LIB"mstr_standard";
"B \NAC \NWC"9;
"S \NAC"
BN"40"70;
%"TAP"
"6","(-5575,3575)","0","mstr_standard","I63";
;
HDL_TAP"TRUE"
BODY_TYPE"PLUMBING"
CDS_LIB"mstr_standard";
"B \NAC \NWC"9;
"S \NAC"
BN"41"71;
%"TAP"
"6","(-5575,3625)","0","mstr_standard","I64";
;
HDL_TAP"TRUE"
BODY_TYPE"PLUMBING"
CDS_LIB"mstr_standard";
"B \NAC \NWC"9;
"S \NAC"
BN"42"72;
%"TAP"
"6","(-5575,3675)","0","mstr_standard","I65";
;
HDL_TAP"TRUE"
BODY_TYPE"PLUMBING"
CDS_LIB"mstr_standard";
"B \NAC \NWC"9;
"S \NAC"
BN"43"73;
%"TAP"
"6","(-5575,3725)","0","mstr_standard","I66";
;
HDL_TAP"TRUE"
BODY_TYPE"PLUMBING"
CDS_LIB"mstr_standard";
"B \NAC \NWC"9;
"S \NAC"
BN"44"74;
%"TAP"
"6","(-5575,3775)","0","mstr_standard","I67";
;
HDL_TAP"TRUE"
BODY_TYPE"PLUMBING"
CDS_LIB"mstr_standard";
"B \NAC \NWC"9;
"S \NAC"
BN"45"75;
%"TAP"
"6","(-5575,3825)","0","mstr_standard","I68";
;
HDL_TAP"TRUE"
BODY_TYPE"PLUMBING"
CDS_LIB"mstr_standard";
"B \NAC \NWC"9;
"S \NAC"
BN"46"76;
%"TAP"
"6","(-5575,3875)","0","mstr_standard","I69";
;
HDL_TAP"TRUE"
BODY_TYPE"PLUMBING"
CDS_LIB"mstr_standard";
"B \NAC \NWC"9;
"S \NAC"
BN"47"77;
%"TAP"
"6","(-5575,775)","0","mstr_standard","I7";
;
HDL_TAP"TRUE"
BODY_TYPE"PLUMBING"
CDS_LIB"mstr_standard";
"B \NAC \NWC"10;
"S \NAC"
BN"3"40;
%"TAP"
"6","(-5575,3925)","0","mstr_standard","I70";
;
HDL_TAP"TRUE"
BODY_TYPE"PLUMBING"
CDS_LIB"mstr_standard";
"B \NAC \NWC"9;
"S \NAC"
BN"48"78;
%"TAP"
"6","(-5575,3975)","0","mstr_standard","I71";
;
HDL_TAP"TRUE"
BODY_TYPE"PLUMBING"
CDS_LIB"mstr_standard";
"B \NAC \NWC"9;
"S \NAC"
BN"49"79;
%"TAP"
"6","(-5575,4025)","0","mstr_standard","I73";
;
HDL_TAP"TRUE"
BODY_TYPE"PLUMBING"
CDS_LIB"mstr_standard";
"B \NAC \NWC"9;
"S \NAC"
BN"50"80;
%"TAP"
"6","(-5575,4075)","0","mstr_standard","I74";
;
HDL_TAP"TRUE"
BODY_TYPE"PLUMBING"
CDS_LIB"mstr_standard";
"B \NAC \NWC"9;
"S \NAC"
BN"51"81;
%"TAP"
"6","(-5575,4125)","0","mstr_standard","I75";
;
HDL_TAP"TRUE"
BODY_TYPE"PLUMBING"
CDS_LIB"mstr_standard";
"B \NAC \NWC"9;
"S \NAC"
BN"52"82;
%"TAP"
"6","(-5575,4175)","0","mstr_standard","I76";
;
HDL_TAP"TRUE"
BODY_TYPE"PLUMBING"
CDS_LIB"mstr_standard";
"B \NAC \NWC"9;
"S \NAC"
BN"53"83;
%"TAP"
"6","(-5575,4225)","0","mstr_standard","I77";
;
HDL_TAP"TRUE"
BODY_TYPE"PLUMBING"
CDS_LIB"mstr_standard";
"B \NAC \NWC"9;
"S \NAC"
BN"54"84;
%"TAP"
"6","(-5575,4275)","0","mstr_standard","I78";
;
HDL_TAP"TRUE"
BODY_TYPE"PLUMBING"
CDS_LIB"mstr_standard";
"B \NAC \NWC"9;
"S \NAC"
BN"55"85;
%"TAP"
"6","(-5575,4325)","0","mstr_standard","I79";
;
HDL_TAP"TRUE"
BODY_TYPE"PLUMBING"
CDS_LIB"mstr_standard";
"B \NAC \NWC"9;
"S \NAC"
BN"56"86;
%"TAP"
"6","(-5575,725)","0","mstr_standard","I8";
;
HDL_TAP"TRUE"
BODY_TYPE"PLUMBING"
CDS_LIB"mstr_standard";
"B \NAC \NWC"10;
"S \NAC"
BN"2"39;
%"TAP"
"6","(-5575,4375)","0","mstr_standard","I80";
;
HDL_TAP"TRUE"
BODY_TYPE"PLUMBING"
CDS_LIB"mstr_standard";
"B \NAC \NWC"9;
"S \NAC"
BN"57"87;
%"TAP"
"6","(-5575,4425)","0","mstr_standard","I81";
;
HDL_TAP"TRUE"
BODY_TYPE"PLUMBING"
CDS_LIB"mstr_standard";
"B \NAC \NWC"9;
"S \NAC"
BN"58"88;
%"TAP"
"6","(-5575,4475)","0","mstr_standard","I82";
;
HDL_TAP"TRUE"
BODY_TYPE"PLUMBING"
CDS_LIB"mstr_standard";
"B \NAC \NWC"9;
"S \NAC"
BN"59"89;
%"TAP"
"6","(-5575,4525)","0","mstr_standard","I83";
;
HDL_TAP"TRUE"
BODY_TYPE"PLUMBING"
CDS_LIB"mstr_standard";
"B \NAC \NWC"9;
"S \NAC"
BN"60"90;
%"TAP"
"6","(-5575,4575)","0","mstr_standard","I84";
;
HDL_TAP"TRUE"
BODY_TYPE"PLUMBING"
CDS_LIB"mstr_standard";
"B \NAC \NWC"9;
"S \NAC"
BN"61"91;
%"TAP"
"6","(-5575,4625)","0","mstr_standard","I85";
;
HDL_TAP"TRUE"
BODY_TYPE"PLUMBING"
CDS_LIB"mstr_standard";
"B \NAC \NWC"9;
"S \NAC"
BN"62"92;
%"TAP"
"6","(-5575,4675)","0","mstr_standard","I86";
;
HDL_TAP"TRUE"
BODY_TYPE"PLUMBING"
CDS_LIB"mstr_standard";
"B \NAC \NWC"9;
"S \NAC"
BN"63"93;
%"TAP"
"6","(-2850,775)","2","mstr_standard","I87";
;
HDL_TAP"TRUE"
BODY_TYPE"PLUMBING"
CDS_LIB"mstr_standard";
"B \NAC \NWC"4;
"S \NAC"
BN"1"116;
%"TAP"
"6","(-2850,725)","2","mstr_standard","I88";
;
HDL_TAP"TRUE"
BODY_TYPE"PLUMBING"
CDS_LIB"mstr_standard";
"B \NAC \NWC"4;
"S \NAC"
BN"0"115;
%"TAP"
"6","(-2850,825)","2","mstr_standard","I89";
;
HDL_TAP"TRUE"
BODY_TYPE"PLUMBING"
CDS_LIB"mstr_standard";
"B \NAC \NWC"5;
"S \NAC"
BN"0"113;
%"TAP"
"6","(-5575,875)","0","mstr_standard","I9";
;
HDL_TAP"TRUE"
BODY_TYPE"PLUMBING"
CDS_LIB"mstr_standard";
"B \NAC \NWC"11;
"S \NAC"
BN"1"34;
%"TAP"
"6","(-2850,875)","2","mstr_standard","I90";
;
HDL_TAP"TRUE"
BODY_TYPE"PLUMBING"
CDS_LIB"mstr_standard";
"B \NAC \NWC"5;
"S \NAC"
BN"1"114;
%"TAP"
"6","(-2850,1075)","2","mstr_standard","I91";
;
HDL_TAP"TRUE"
BODY_TYPE"PLUMBING"
CDS_LIB"mstr_standard";
"B \NAC \NWC"7;
"S \NAC"
BN"2"103;
%"TAP"
"6","(-2850,1025)","2","mstr_standard","I92";
;
HDL_TAP"TRUE"
BODY_TYPE"PLUMBING"
CDS_LIB"mstr_standard";
"B \NAC \NWC"7;
"S \NAC"
BN"1"102;
%"TAP"
"6","(-2850,975)","2","mstr_standard","I93";
;
HDL_TAP"TRUE"
BODY_TYPE"PLUMBING"
CDS_LIB"mstr_standard";
"B \NAC \NWC"7;
"S \NAC"
BN"0"101;
%"TAP"
"6","(-2850,1175)","2","mstr_standard","I94";
;
HDL_TAP"TRUE"
BODY_TYPE"PLUMBING"
CDS_LIB"mstr_standard";
"B \NAC \NWC"7;
"S \NAC"
BN"4"105;
%"TAP"
"6","(-2850,1125)","2","mstr_standard","I95";
;
HDL_TAP"TRUE"
BODY_TYPE"PLUMBING"
CDS_LIB"mstr_standard";
"B \NAC \NWC"7;
"S \NAC"
BN"3"104;
%"TAP"
"6","(-2850,1225)","2","mstr_standard","I96";
;
HDL_TAP"TRUE"
BODY_TYPE"PLUMBING"
CDS_LIB"mstr_standard";
"B \NAC \NWC"7;
"S \NAC"
BN"5"106;
%"TAP"
"6","(-2850,1275)","2","mstr_standard","I97";
;
HDL_TAP"TRUE"
BODY_TYPE"PLUMBING"
CDS_LIB"mstr_standard";
"B \NAC \NWC"7;
"S \NAC"
BN"6"107;
%"TAP"
"6","(-2850,1325)","2","mstr_standard","I98";
;
HDL_TAP"TRUE"
BODY_TYPE"PLUMBING"
CDS_LIB"mstr_standard";
"B \NAC \NWC"7;
"S \NAC"
BN"7"108;
%"TAP"
"6","(-2850,1425)","2","mstr_standard","I99";
;
HDL_TAP"TRUE"
BODY_TYPE"PLUMBING"
CDS_LIB"mstr_standard";
"B \NAC \NWC"8;
"S \NAC"
BN"0"94;
END.
